(kicad_pcb
	(version 20260206)
	(generator "pcbnew")
	(generator_version "10.0")
	(general
		(thickness 1.6)
		(legacy_teardrops no)
	)
	(paper "A4")
	(title_block
		(title "9054_F0T_PDB_BD_GPU_F_V04_1213_1550_OCP.brd")
		(comment 1 "Grand Teton / footprints 1-7 of 608")
	)
	(layers
		(0 "F.Cu" signal "TOP")
		(4 "In1.Cu" signal "GND")
		(6 "In2.Cu" signal "IN1")
		(8 "In3.Cu" signal "GND1")
		(10 "In4.Cu" signal "VCC")
		(12 "In5.Cu" signal "VCC1")
		(14 "In6.Cu" signal "GND2")
		(16 "In7.Cu" signal "IN2")
		(18 "In8.Cu" signal "GND3")
		(2 "B.Cu" signal "BOTTOM")
		(9 "F.Adhes" user "F.Adhesive")
		(11 "B.Adhes" user "B.Adhesive")
		(13 "F.Paste" user "Package Geometry/Pastemask Top")
		(15 "B.Paste" user "Package Geometry/Pastemask Bottom")
		(5 "F.SilkS" user "Ref Des/Silkscreen Top")
		(7 "B.SilkS" user "Ref Des/Silkscreen Bottom")
		(1 "F.Mask" user "Board Geometry/Soldermask Top")
		(3 "B.Mask" user "Board Geometry/Soldermask Bottom")
		(17 "Dwgs.User" user "User.Drawings")
		(19 "Cmts.User" user "User.Comments")
		(21 "Eco1.User" user "User.Eco1")
		(23 "Eco2.User" user "User.Eco2")
		(25 "Edge.Cuts" user "Board Geometry/Outline")
		(27 "Margin" user)
		(31 "F.CrtYd" user "Package Geometry/Place Bound Top")
		(29 "B.CrtYd" user "Package Geometry/Place Bound Bottom")
		(35 "F.Fab" user "Ref Des/Assembly Top")
		(33 "B.Fab" user "Ref Des/Assembly Bottom")
	)
	(footprint ""
		(layer "F.Cu")
		(at 439.547 -63.5 180)
		(property "Reference" "R5929"
			(at 0 0 180)
			(layer "F.SilkS")
			(hide yes)
			(effects
				(font
					(size 1.27 1.27)
				)
			)
		)
		(property "Value" ""
			(at 0 0 180)
			(layer "F.Fab")
			(effects
				(font
					(size 1.27 1.27)
				)
			)
		)
		(duplicate_pad_numbers_are_jumpers no)
		(fp_line
			(start 0.7874 0.4064)
			(end -0.7874 0.4064)
			(stroke
				(width 0.1524)
				(type default)
			)
			(layer "F.SilkS")
		)
		(fp_line
			(start 0.7874 -0.4064)
			(end 0.7874 0.4064)
			(stroke
				(width 0.1524)
				(type default)
			)
			(layer "F.SilkS")
		)
		(fp_line
			(start -0.7874 0.4064)
			(end -0.7874 -0.4064)
			(stroke
				(width 0.1524)
				(type default)
			)
			(layer "F.SilkS")
		)
		(fp_line
			(start -0.7874 -0.4064)
			(end 0.7874 -0.4064)
			(stroke
				(width 0.1524)
				(type default)
			)
			(layer "F.SilkS")
		)
		(fp_line
			(start 0.67945 0.3048)
			(end 0.120396 0.3048)
			(stroke
				(width 0.1)
				(type default)
			)
			(layer "F.Fab")
		)
		(fp_line
			(start 0.67945 -0.3048)
			(end 0.67945 0.3048)
			(stroke
				(width 0.1)
				(type default)
			)
			(layer "F.Fab")
		)
		(fp_line
			(start 0.12065 -0.2794)
			(end 0.12065 -0.3048)
			(stroke
				(width 0.1)
				(type default)
			)
			(layer "F.Fab")
		)
		(fp_line
			(start 0.12065 -0.3048)
			(end 0.67945 -0.3048)
			(stroke
				(width 0.1)
				(type default)
			)
			(layer "F.Fab")
		)
		(fp_line
			(start 0.120396 0.3048)
			(end 0.120396 0.2794)
			(stroke
				(width 0.1)
				(type default)
			)
			(layer "F.Fab")
		)
		(fp_line
			(start 0.120396 0.2794)
			(end -0.12065 0.2794)
			(stroke
				(width 0.1)
				(type default)
			)
			(layer "F.Fab")
		)
		(fp_line
			(start -0.12065 0.3048)
			(end -0.67945 0.3048)
			(stroke
				(width 0.1)
				(type default)
			)
			(layer "F.Fab")
		)
		(fp_line
			(start -0.12065 0.2794)
			(end -0.12065 0.3048)
			(stroke
				(width 0.1)
				(type default)
			)
			(layer "F.Fab")
		)
		(fp_line
			(start -0.12065 -0.2794)
			(end 0.12065 -0.2794)
			(stroke
				(width 0.1)
				(type default)
			)
			(layer "F.Fab")
		)
		(fp_line
			(start -0.12065 -0.305054)
			(end -0.12065 -0.2794)
			(stroke
				(width 0.1)
				(type default)
			)
			(layer "F.Fab")
		)
		(fp_line
			(start -0.67945 0.3048)
			(end -0.67945 -0.305054)
			(stroke
				(width 0.1)
				(type default)
			)
			(layer "F.Fab")
		)
		(fp_line
			(start -0.67945 -0.305054)
			(end -0.12065 -0.305054)
			(stroke
				(width 0.1)
				(type default)
			)
			(layer "F.Fab")
		)
		(pad "1" smd circle
			(at -0.40005 0 180)
			(size 0 0)
			(layers "F.Cu" "F.Mask" "F.Paste")
			(net "P3V3_AUX")
		)
		(pad "2" smd circle
			(at 0.40005 0 180)
			(size 0 0)
			(layers "F.Cu" "F.Mask" "F.Paste")
			(net "LED_D6_R1")
		)
	)
	(footprint ""
		(layer "F.Cu")
		(at 445.741806 -90.888058 180)
		(property "Reference" "PC56"
			(at 0 0 180)
			(layer "F.SilkS")
			(hide yes)
			(effects
				(font
					(size 1.27 1.27)
				)
			)
		)
		(property "Value" ""
			(at 0 0 180)
			(layer "F.Fab")
			(effects
				(font
					(size 1.27 1.27)
				)
			)
		)
		(duplicate_pad_numbers_are_jumpers no)
		(fp_line
			(start 1.524 0.762)
			(end -1.524 0.762)
			(stroke
				(width 0.1524)
				(type default)
			)
			(layer "F.SilkS")
		)
		(fp_line
			(start 1.524 -0.762)
			(end 1.524 0.762)
			(stroke
				(width 0.1524)
				(type default)
			)
			(layer "F.SilkS")
		)
		(fp_line
			(start -1.524 0.762)
			(end -1.524 -0.762)
			(stroke
				(width 0.1524)
				(type default)
			)
			(layer "F.SilkS")
		)
		(fp_line
			(start -1.524 -0.762)
			(end 1.524 -0.762)
			(stroke
				(width 0.1524)
				(type default)
			)
			(layer "F.SilkS")
		)
		(fp_line
			(start 1.1049 0.724916)
			(end 1.1049 -0.724916)
			(stroke
				(width 0.1)
				(type default)
			)
			(layer "F.Fab")
		)
		(fp_line
			(start 1.1049 -0.724916)
			(end -1.1049 -0.724916)
			(stroke
				(width 0.1)
				(type default)
			)
			(layer "F.Fab")
		)
		(fp_line
			(start -1.1049 0.724916)
			(end 1.1049 0.724916)
			(stroke
				(width 0.1)
				(type default)
			)
			(layer "F.Fab")
		)
		(fp_line
			(start -1.1049 -0.724916)
			(end -1.1049 0.724916)
			(stroke
				(width 0.1)
				(type default)
			)
			(layer "F.Fab")
		)
		(pad "1" smd rect
			(at -0.889 0)
			(size 1.016 1.27)
			(layers "F.Cu" "F.Mask" "F.Paste")
			(net "SW_P3V3_HPDB_FLT")
		)
		(pad "2" smd rect
			(at 0.889 0)
			(size 1.016 1.27)
			(layers "F.Cu" "F.Mask" "F.Paste")
			(net "GND")
		)
	)
	(footprint ""
		(layer "F.Cu")
		(at 238.810038 -79.624936)
		(property "Reference" "H34"
			(at -1.9812 -4.079748 0)
			(unlocked yes)
			(layer "B.SilkS")
			(effects
				(font
					(size 0.7874 0.5842)
					(thickness 0.1524)
				)
				(justify left mirror)
			)
		)
		(property "Value" ""
			(at 0 0 0)
			(layer "F.Fab")
			(effects
				(font
					(size 1.27 1.27)
				)
			)
		)
		(duplicate_pad_numbers_are_jumpers no)
		(pad "1" thru_hole circle
			(at 0 0)
			(size 8.001 8.001)
			(drill 4.2418)
			(layers "*.Cu" "*.Mask")
			(remove_unused_layers no)
			(net "TP_H34")
			(clearance -1.6256)
			(padstack
				(mode front_inner_back)
				(layer "Inner"
					(shape circle)
					(size 6.0198 6.0198)
					(clearance -0.635)
				)
				(layer "B.Cu"
					(shape circle)
					(size 8.001 8.001)
					(clearance -1.6256)
				)
			)
		)
		(zone
			(layers "F.Cu" "B.Cu" "In1.Cu" "In2.Cu" "In3.Cu" "In4.Cu" "In5.Cu" "In6.Cu"
				"In7.Cu" "In8.Cu"
			)
			(hatch none 0.5)
			(connect_pads
				(clearance 0)
			)
			(min_thickness 0.25)
			(keepout
				(tracks not_allowed)
				(vias allowed)
				(pads allowed)
				(copperpour not_allowed)
				(footprints allowed)
			)
			(placement
				(enabled no)
				(sheetname "")
			)
			(fill
				(thermal_gap 0.5)
				(thermal_bridge_width 0.5)
				(island_removal_mode 0)
			)
			(polygon
				(pts
					(arc
						(start 242.320064 -79.624936)
						(mid 235.300012 -79.624936)
						(end 242.320064 -79.624936)
					)
				)
			)
		)
	)
	(footprint ""
		(layer "F.Cu")
		(at 449.8594 -62.23 -90)
		(property "Reference" "PC49"
			(at 0 0 270)
			(layer "F.SilkS")
			(hide yes)
			(effects
				(font
					(size 1.27 1.27)
				)
			)
		)
		(property "Value" ""
			(at 0 0 270)
			(layer "F.Fab")
			(effects
				(font
					(size 1.27 1.27)
				)
			)
		)
		(duplicate_pad_numbers_are_jumpers no)
		(fp_line
			(start -1.524 0.762)
			(end -1.524 -0.762)
			(stroke
				(width 0.1524)
				(type default)
			)
			(layer "F.SilkS")
		)
		(fp_line
			(start 1.524 0.762)
			(end -1.524 0.762)
			(stroke
				(width 0.1524)
				(type default)
			)
			(layer "F.SilkS")
		)
		(fp_line
			(start -1.524 -0.762)
			(end 1.524 -0.762)
			(stroke
				(width 0.1524)
				(type default)
			)
			(layer "F.SilkS")
		)
		(fp_line
			(start 1.524 -0.762)
			(end 1.524 0.762)
			(stroke
				(width 0.1524)
				(type default)
			)
			(layer "F.SilkS")
		)
		(fp_line
			(start -1.1049 0.724916)
			(end 1.1049 0.724916)
			(stroke
				(width 0.1)
				(type default)
			)
			(layer "F.Fab")
		)
		(fp_line
			(start 1.1049 0.724916)
			(end 1.1049 -0.724916)
			(stroke
				(width 0.1)
				(type default)
			)
			(layer "F.Fab")
		)
		(fp_line
			(start -1.1049 -0.724916)
			(end -1.1049 0.724916)
			(stroke
				(width 0.1)
				(type default)
			)
			(layer "F.Fab")
		)
		(fp_line
			(start 1.1049 -0.724916)
			(end -1.1049 -0.724916)
			(stroke
				(width 0.1)
				(type default)
			)
			(layer "F.Fab")
		)
		(pad "1" smd rect
			(at -0.889 0 90)
			(size 1.016 1.27)
			(layers "F.Cu" "F.Mask" "F.Paste")
			(net "P3V3_AUX")
		)
		(pad "2" smd rect
			(at 0.889 0 90)
			(size 1.016 1.27)
			(layers "F.Cu" "F.Mask" "F.Paste")
			(net "GND")
		)
	)
	(footprint ""
		(layer "F.Cu")
		(at 450.42074 -83.393788)
		(property "Reference" "PR113"
			(at 0 0 0)
			(layer "F.SilkS")
			(hide yes)
			(effects
				(font
					(size 1.27 1.27)
				)
			)
		)
		(property "Value" ""
			(at 0 0 0)
			(layer "F.Fab")
			(effects
				(font
					(size 1.27 1.27)
				)
			)
		)
		(duplicate_pad_numbers_are_jumpers no)
		(fp_line
			(start -0.7874 -0.4064)
			(end 0.7874 -0.4064)
			(stroke
				(width 0.1524)
				(type default)
			)
			(layer "F.SilkS")
		)
		(fp_line
			(start -0.7874 0.4064)
			(end -0.7874 -0.4064)
			(stroke
				(width 0.1524)
				(type default)
			)
			(layer "F.SilkS")
		)
		(fp_line
			(start 0.7874 -0.4064)
			(end 0.7874 0.4064)
			(stroke
				(width 0.1524)
				(type default)
			)
			(layer "F.SilkS")
		)
		(fp_line
			(start 0.7874 0.4064)
			(end -0.7874 0.4064)
			(stroke
				(width 0.1524)
				(type default)
			)
			(layer "F.SilkS")
		)
		(fp_line
			(start -0.67945 -0.305054)
			(end -0.12065 -0.305054)
			(stroke
				(width 0.1)
				(type default)
			)
			(layer "F.Fab")
		)
		(fp_line
			(start -0.67945 0.3048)
			(end -0.67945 -0.305054)
			(stroke
				(width 0.1)
				(type default)
			)
			(layer "F.Fab")
		)
		(fp_line
			(start -0.12065 -0.305054)
			(end -0.12065 -0.2794)
			(stroke
				(width 0.1)
				(type default)
			)
			(layer "F.Fab")
		)
		(fp_line
			(start -0.12065 -0.2794)
			(end 0.12065 -0.2794)
			(stroke
				(width 0.1)
				(type default)
			)
			(layer "F.Fab")
		)
		(fp_line
			(start -0.12065 0.2794)
			(end -0.12065 0.3048)
			(stroke
				(width 0.1)
				(type default)
			)
			(layer "F.Fab")
		)
		(fp_line
			(start -0.12065 0.3048)
			(end -0.67945 0.3048)
			(stroke
				(width 0.1)
				(type default)
			)
			(layer "F.Fab")
		)
		(fp_line
			(start 0.120396 0.2794)
			(end -0.12065 0.2794)
			(stroke
				(width 0.1)
				(type default)
			)
			(layer "F.Fab")
		)
		(fp_line
			(start 0.120396 0.3048)
			(end 0.120396 0.2794)
			(stroke
				(width 0.1)
				(type default)
			)
			(layer "F.Fab")
		)
		(fp_line
			(start 0.12065 -0.3048)
			(end 0.67945 -0.3048)
			(stroke
				(width 0.1)
				(type default)
			)
			(layer "F.Fab")
		)
		(fp_line
			(start 0.12065 -0.2794)
			(end 0.12065 -0.3048)
			(stroke
				(width 0.1)
				(type default)
			)
			(layer "F.Fab")
		)
		(fp_line
			(start 0.67945 -0.3048)
			(end 0.67945 0.3048)
			(stroke
				(width 0.1)
				(type default)
			)
			(layer "F.Fab")
		)
		(fp_line
			(start 0.67945 0.3048)
			(end 0.120396 0.3048)
			(stroke
				(width 0.1)
				(type default)
			)
			(layer "F.Fab")
		)
		(pad "1" smd circle
			(at -0.40005 0)
			(size 0 0)
			(layers "F.Cu" "F.Mask" "F.Paste")
			(net "P3V3_HPDB_CS")
		)
		(pad "2" smd circle
			(at 0.40005 0)
			(size 0 0)
			(layers "F.Cu" "F.Mask" "F.Paste")
			(net "GND")
		)
	)
	(footprint ""
		(layer "F.Cu")
		(at 124.483876 -40.8178)
		(property "Reference" "PQ41"
			(at 8.913114 -3.609848 0)
			(unlocked yes)
			(layer "F.SilkS")
			(effects
				(font
					(size 0.7874 0.5842)
					(thickness 0.1524)
				)
				(justify left)
			)
		)
		(property "Value" ""
			(at 0 0 0)
			(layer "F.Fab")
			(effects
				(font
					(size 1.27 1.27)
				)
			)
		)
		(duplicate_pad_numbers_are_jumpers no)
		(fp_line
			(start -7.649972 -4.99999)
			(end -7.649972 -3.3274)
			(stroke
				(width 0.1524)
				(type default)
			)
			(layer "F.SilkS")
		)
		(fp_line
			(start -7.649972 -1.7526)
			(end -7.649972 1.7526)
			(stroke
				(width 0.1524)
				(type default)
			)
			(layer "F.SilkS")
		)
		(fp_line
			(start -7.649972 3.3274)
			(end -7.649972 4.99999)
			(stroke
				(width 0.1524)
				(type default)
			)
			(layer "F.SilkS")
		)
		(fp_line
			(start -7.649972 4.99999)
			(end 5.115814 4.99999)
			(stroke
				(width 0.1524)
				(type default)
			)
			(layer "F.SilkS")
		)
		(fp_line
			(start 5.115814 -4.99999)
			(end -7.649972 -4.99999)
			(stroke
				(width 0.1524)
				(type default)
			)
			(layer "F.SilkS")
		)
		(fp_line
			(start 7.630414 4.99999)
			(end 7.649972 4.99999)
			(stroke
				(width 0.1524)
				(type default)
			)
			(layer "F.SilkS")
		)
		(fp_line
			(start 7.649972 -4.99999)
			(end 7.630414 -4.99999)
			(stroke
				(width 0.1524)
				(type default)
			)
			(layer "F.SilkS")
		)
		(fp_line
			(start 7.649972 4.99999)
			(end 7.649972 -4.99999)
			(stroke
				(width 0.1524)
				(type default)
			)
			(layer "F.SilkS")
		)
		(fp_line
			(start -7.649972 -4.99999)
			(end -7.649972 4.99999)
			(stroke
				(width 0.1)
				(type default)
			)
			(layer "F.Fab")
		)
		(fp_line
			(start -7.649972 4.99999)
			(end 7.649972 4.99999)
			(stroke
				(width 0.1)
				(type default)
			)
			(layer "F.Fab")
		)
		(fp_line
			(start 7.649972 -4.99999)
			(end -7.649972 -4.99999)
			(stroke
				(width 0.1)
				(type default)
			)
			(layer "F.Fab")
		)
		(fp_line
			(start 7.649972 4.99999)
			(end 7.649972 -4.99999)
			(stroke
				(width 0.1)
				(type default)
			)
			(layer "F.Fab")
		)
		(pad "D" smd circle
			(at 2.15011 0)
			(size 0 0)
			(layers "F.Cu" "F.Mask" "F.Paste")
			(net "P52V_HS2_DRAIN_2")
		)
		(pad "G" smd rect
			(at -7.050024 -2.54 270)
			(size 1.3208 3.0988)
			(layers "F.Cu" "F.Mask" "F.Paste")
			(net "P52V_HS2_GATE4")
		)
		(pad "S" smd rect
			(at -7.050024 2.54 270)
			(size 1.3208 3.0988)
			(layers "F.Cu" "F.Mask" "F.Paste")
			(net "P52V_HS2")
		)
		(zone
			(layer "F.Cu")
			(hatch none 0.5)
			(connect_pads
				(clearance 0)
			)
			(min_thickness 0.25)
			(keepout
				(tracks not_allowed)
				(vias allowed)
				(pads allowed)
				(copperpour not_allowed)
				(footprints allowed)
			)
			(placement
				(enabled no)
				(sheetname "")
			)
			(fill
				(thermal_gap 0.5)
				(thermal_bridge_width 0.5)
				(island_removal_mode 0)
			)
			(polygon
				(pts
					(xy 129.665476 -45.7962) (xy 116.838476 -45.7962) (xy 116.838476 -44.069) (xy 119.048276 -44.069)
					(xy 119.048276 -42.6466) (xy 116.838476 -42.6466) (xy 116.838476 -38.989) (xy 119.048276 -38.989)
					(xy 119.048276 -37.5666) (xy 116.838476 -37.5666) (xy 116.838476 -35.8394) (xy 129.665476 -35.8394)
					(xy 129.665476 -37.0078) (xy 123.467876 -37.0078) (xy 123.467876 -44.6278) (xy 129.665476 -44.6278)
				)
			)
		)
	)
	(footprint ""
		(layer "F.Cu")
		(at 413.512 -46.482)
		(property "Reference" "R48"
			(at 0 0 0)
			(layer "F.SilkS")
			(hide yes)
			(effects
				(font
					(size 1.27 1.27)
				)
			)
		)
		(property "Value" ""
			(at 0 0 0)
			(layer "F.Fab")
			(effects
				(font
					(size 1.27 1.27)
				)
			)
		)
		(duplicate_pad_numbers_are_jumpers no)
		(fp_line
			(start -0.7874 -0.4064)
			(end 0.7874 -0.4064)
			(stroke
				(width 0.1524)
				(type default)
			)
			(layer "F.SilkS")
		)
		(fp_line
			(start -0.7874 0.4064)
			(end -0.7874 -0.4064)
			(stroke
				(width 0.1524)
				(type default)
			)
			(layer "F.SilkS")
		)
		(fp_line
			(start 0.7874 -0.4064)
			(end 0.7874 0.4064)
			(stroke
				(width 0.1524)
				(type default)
			)
			(layer "F.SilkS")
		)
		(fp_line
			(start 0.7874 0.4064)
			(end -0.7874 0.4064)
			(stroke
				(width 0.1524)
				(type default)
			)
			(layer "F.SilkS")
		)
		(fp_line
			(start -0.67945 -0.305054)
			(end -0.12065 -0.305054)
			(stroke
				(width 0.1)
				(type default)
			)
			(layer "F.Fab")
		)
		(fp_line
			(start -0.67945 0.3048)
			(end -0.67945 -0.305054)
			(stroke
				(width 0.1)
				(type default)
			)
			(layer "F.Fab")
		)
		(fp_line
			(start -0.12065 -0.305054)
			(end -0.12065 -0.2794)
			(stroke
				(width 0.1)
				(type default)
			)
			(layer "F.Fab")
		)
		(fp_line
			(start -0.12065 -0.2794)
			(end 0.12065 -0.2794)
			(stroke
				(width 0.1)
				(type default)
			)
			(layer "F.Fab")
		)
		(fp_line
			(start -0.12065 0.2794)
			(end -0.12065 0.3048)
			(stroke
				(width 0.1)
				(type default)
			)
			(layer "F.Fab")
		)
		(fp_line
			(start -0.12065 0.3048)
			(end -0.67945 0.3048)
			(stroke
				(width 0.1)
				(type default)
			)
			(layer "F.Fab")
		)
		(fp_line
			(start 0.120396 0.2794)
			(end -0.12065 0.2794)
			(stroke
				(width 0.1)
				(type default)
			)
			(layer "F.Fab")
		)
		(fp_line
			(start 0.120396 0.3048)
			(end 0.120396 0.2794)
			(stroke
				(width 0.1)
				(type default)
			)
			(layer "F.Fab")
		)
		(fp_line
			(start 0.12065 -0.3048)
			(end 0.67945 -0.3048)
			(stroke
				(width 0.1)
				(type default)
			)
			(layer "F.Fab")
		)
		(fp_line
			(start 0.12065 -0.2794)
			(end 0.12065 -0.3048)
			(stroke
				(width 0.1)
				(type default)
			)
			(layer "F.Fab")
		)
		(fp_line
			(start 0.67945 -0.3048)
			(end 0.67945 0.3048)
			(stroke
				(width 0.1)
				(type default)
			)
			(layer "F.Fab")
		)
		(fp_line
			(start 0.67945 0.3048)
			(end 0.120396 0.3048)
			(stroke
				(width 0.1)
				(type default)
			)
			(layer "F.Fab")
		)
		(pad "1" smd circle
			(at -0.40005 0)
			(size 0 0)
			(layers "F.Cu" "F.Mask" "F.Paste")
			(net "P3V3_AUX")
		)
		(pad "2" smd circle
			(at 0.40005 0)
			(size 0 0)
			(layers "F.Cu" "F.Mask" "F.Paste")
			(net "PU_U8_PIN1")
		)
	)
)
